# T6G (Grand Teton) — schematic netlist excerpt (pin names and nets, part order shuffled) for the footprints in the layout excerpt that follows; sources: Cadence DE-HDL packaged netlist, KiCad conversion of 04192023_DAF0TMB3IC0_F0TG_MB_C_brd_V02_OCP.brd

PC6004  Q_CAP  0.1UF 25V 10% X7R  pkg 0402  page 211 : A = P12V_AUX ; B = GND
R697  Q_RES  0 5% CHIP  pkg 0201LF  page 355 : A = SMB_RT_CPU1_P3_ROM_R_SCL ; B = SMB_RT_CPU1_P3_ROM_SCL
R583  Q_RES  4.7K 5% EMPTY  pkg 0402LF  page 55 : A = RST_CPU1_RSMRST_N ; B = PVDD18_S5_P1

(kicad_pcb
	(version 20260206)
	(generator "pcbnew")
	(generator_version "10.0")
	(general
		(thickness 1.6)
		(legacy_teardrops no)
	)
	(paper "A4")
	(title_block
		(title "04192023_DAF0TMB3IC0_F0TG_MB_C_brd_V02_OCP.brd")
		(comment 1 "Grand Teton / footprints 1131-1133 of 8354")
	)
	(layers
		(0 "F.Cu" signal "TOP")
		(4 "In1.Cu" signal "GND")
		(6 "In2.Cu" signal "IN1")
		(8 "In3.Cu" signal "GND1")
		(10 "In4.Cu" signal "IN2")
		(12 "In5.Cu" signal "GND2")
		(14 "In6.Cu" signal "IN3")
		(16 "In7.Cu" signal "GND3")
		(18 "In8.Cu" signal "VCC")
		(20 "In9.Cu" signal "VCC1")
		(22 "In10.Cu" signal "GND4")
		(24 "In11.Cu" signal "IN4")
		(26 "In12.Cu" signal "GND5")
		(28 "In13.Cu" signal "IN5")
		(30 "In14.Cu" signal "GND6")
		(32 "In15.Cu" signal "IN6")
		(34 "In16.Cu" signal "GND7")
		(2 "B.Cu" signal "BOTTOM")
		(9 "F.Adhes" user "F.Adhesive")
		(11 "B.Adhes" user "B.Adhesive")
		(13 "F.Paste" user "Package Geometry/Pastemask Top")
		(15 "B.Paste" user "Package Geometry/Pastemask Bottom")
		(5 "F.SilkS" user "Ref Des/Silkscreen Top")
		(7 "B.SilkS" user "Ref Des/Silkscreen Bottom")
		(1 "F.Mask" user "Board Geometry/Soldermask Top")
		(3 "B.Mask" user "Board Geometry/Soldermask Bottom")
		(17 "Dwgs.User" user "User.Drawings")
		(19 "Cmts.User" user "User.Comments")
		(21 "Eco1.User" user "User.Eco1")
		(23 "Eco2.User" user "User.Eco2")
		(25 "Edge.Cuts" user "Board Geometry/Outline")
		(27 "Margin" user)
		(31 "F.CrtYd" user "Package Geometry/Place Bound Top")
		(29 "B.CrtYd" user "Package Geometry/Place Bound Bottom")
		(35 "F.Fab" user "Ref Des/Assembly Top")
		(33 "B.Fab" user "Ref Des/Assembly Bottom")
	)
	(footprint ""
		(layer "F.Cu")
		(at 152.849834 -320.699892)
		(property "Reference" "R583"
			(at 0 0 0)
			(layer "F.SilkS")
			(hide yes)
			(effects
				(font
					(size 1.27 1.27)
				)
			)
		)
		(property "Value" ""
			(at 0 0 0)
			(layer "F.Fab")
			(effects
				(font
					(size 1.27 1.27)
				)
			)
		)
		(duplicate_pad_numbers_are_jumpers no)
		(fp_line
			(start -0.7874 -0.4064)
			(end 0.7874 -0.4064)
			(stroke
				(width 0.1524)
				(type default)
			)
			(layer "F.SilkS")
		)
		(fp_line
			(start -0.7874 0.4064)
			(end -0.7874 -0.4064)
			(stroke
				(width 0.1524)
				(type default)
			)
			(layer "F.SilkS")
		)
		(fp_line
			(start 0.7874 -0.4064)
			(end 0.7874 0.4064)
			(stroke
				(width 0.1524)
				(type default)
			)
			(layer "F.SilkS")
		)
		(fp_line
			(start 0.7874 0.4064)
			(end -0.7874 0.4064)
			(stroke
				(width 0.1524)
				(type default)
			)
			(layer "F.SilkS")
		)
		(fp_line
			(start -0.67945 -0.305054)
			(end -0.12065 -0.305054)
			(stroke
				(width 0.1)
				(type default)
			)
			(layer "F.Fab")
		)
		(fp_line
			(start -0.67945 0.3048)
			(end -0.67945 -0.305054)
			(stroke
				(width 0.1)
				(type default)
			)
			(layer "F.Fab")
		)
		(fp_line
			(start -0.12065 -0.305054)
			(end -0.12065 -0.2794)
			(stroke
				(width 0.1)
				(type default)
			)
			(layer "F.Fab")
		)
		(fp_line
			(start -0.12065 -0.2794)
			(end 0.12065 -0.2794)
			(stroke
				(width 0.1)
				(type default)
			)
			(layer "F.Fab")
		)
		(fp_line
			(start -0.12065 0.2794)
			(end -0.12065 0.3048)
			(stroke
				(width 0.1)
				(type default)
			)
			(layer "F.Fab")
		)
		(fp_line
			(start -0.12065 0.3048)
			(end -0.67945 0.3048)
			(stroke
				(width 0.1)
				(type default)
			)
			(layer "F.Fab")
		)
		(fp_line
			(start 0.120396 0.2794)
			(end -0.12065 0.2794)
			(stroke
				(width 0.1)
				(type default)
			)
			(layer "F.Fab")
		)
		(fp_line
			(start 0.120396 0.3048)
			(end 0.120396 0.2794)
			(stroke
				(width 0.1)
				(type default)
			)
			(layer "F.Fab")
		)
		(fp_line
			(start 0.12065 -0.3048)
			(end 0.67945 -0.3048)
			(stroke
				(width 0.1)
				(type default)
			)
			(layer "F.Fab")
		)
		(fp_line
			(start 0.12065 -0.2794)
			(end 0.12065 -0.3048)
			(stroke
				(width 0.1)
				(type default)
			)
			(layer "F.Fab")
		)
		(fp_line
			(start 0.67945 -0.3048)
			(end 0.67945 0.3048)
			(stroke
				(width 0.1)
				(type default)
			)
			(layer "F.Fab")
		)
		(fp_line
			(start 0.67945 0.3048)
			(end 0.120396 0.3048)
			(stroke
				(width 0.1)
				(type default)
			)
			(layer "F.Fab")
		)
		(pad "1" smd circle
			(at -0.40005 0)
			(size 0 0)
			(layers "F.Cu" "F.Mask" "F.Paste")
			(net "RST_CPU1_RSMRST_N")
		)
		(pad "2" smd circle
			(at 0.40005 0)
			(size 0 0)
			(layers "F.Cu" "F.Mask" "F.Paste")
			(net "PVDD18_S5_P1")
		)
	)
	(footprint ""
		(layer "F.Cu")
		(at 169.66819 -419.116256 90)
		(property "Reference" "R697"
			(at 0 0 90)
			(layer "F.SilkS")
			(hide yes)
			(effects
				(font
					(size 1.27 1.27)
				)
			)
		)
		(property "Value" ""
			(at 0 0 90)
			(layer "F.Fab")
			(effects
				(font
					(size 1.27 1.27)
				)
			)
		)
		(duplicate_pad_numbers_are_jumpers no)
		(fp_line
			(start 0.32512 -0.175006)
			(end 0.32512 0.175006)
			(stroke
				(width 0.1)
				(type default)
			)
			(layer "F.Fab")
		)
		(fp_line
			(start -0.32512 -0.175006)
			(end 0.32512 -0.175006)
			(stroke
				(width 0.1)
				(type default)
			)
			(layer "F.Fab")
		)
		(fp_line
			(start 0.32512 0.175006)
			(end -0.32512 0.175006)
			(stroke
				(width 0.1)
				(type default)
			)
			(layer "F.Fab")
		)
		(fp_line
			(start -0.32512 0.175006)
			(end -0.32512 -0.175006)
			(stroke
				(width 0.1)
				(type default)
			)
			(layer "F.Fab")
		)
		(pad "1" smd rect
			(at -0.2667 0 90)
			(size 0.3048 0.381)
			(layers "F.Cu" "F.Mask" "F.Paste")
			(net "SMB_RT_CPU1_P3_ROM_R_SCL")
		)
		(pad "2" smd rect
			(at 0.2667 0 270)
			(size 0.3048 0.381)
			(layers "F.Cu" "F.Mask" "F.Paste")
			(net "SMB_RT_CPU1_P3_ROM_SCL")
		)
	)
	(footprint ""
		(layer "F.Cu")
		(at 92.997528 -156.829252)
		(property "Reference" "PC6004"
			(at 0 0 0)
			(layer "F.SilkS")
			(hide yes)
			(effects
				(font
					(size 1.27 1.27)
				)
			)
		)
		(property "Value" ""
			(at 0 0 0)
			(layer "F.Fab")
			(effects
				(font
					(size 1.27 1.27)
				)
			)
		)
		(duplicate_pad_numbers_are_jumpers no)
		(fp_line
			(start -0.7874 -0.4064)
			(end 0.7874 -0.4064)
			(stroke
				(width 0.1524)
				(type default)
			)
			(layer "F.SilkS")
		)
		(fp_line
			(start -0.7874 0.4064)
			(end -0.7874 -0.4064)
			(stroke
				(width 0.1524)
				(type default)
			)
			(layer "F.SilkS")
		)
		(fp_line
			(start 0.7874 -0.4064)
			(end 0.7874 0.4064)
			(stroke
				(width 0.1524)
				(type default)
			)
			(layer "F.SilkS")
		)
		(fp_line
			(start 0.7874 0.4064)
			(end -0.7874 0.4064)
			(stroke
				(width 0.1524)
				(type default)
			)
			(layer "F.SilkS")
		)
		(fp_line
			(start -0.67945 -0.305054)
			(end -0.12065 -0.305054)
			(stroke
				(width 0.1)
				(type default)
			)
			(layer "F.Fab")
		)
		(fp_line
			(start -0.67945 0.3048)
			(end -0.67945 -0.305054)
			(stroke
				(width 0.1)
				(type default)
			)
			(layer "F.Fab")
		)
		(fp_line
			(start -0.12065 -0.305054)
			(end -0.12065 -0.2794)
			(stroke
				(width 0.1)
				(type default)
			)
			(layer "F.Fab")
		)
		(fp_line
			(start -0.12065 -0.2794)
			(end 0.12065 -0.2794)
			(stroke
				(width 0.1)
				(type default)
			)
			(layer "F.Fab")
		)
		(fp_line
			(start -0.12065 0.2794)
			(end -0.12065 0.3048)
			(stroke
				(width 0.1)
				(type default)
			)
			(layer "F.Fab")
		)
		(fp_line
			(start -0.12065 0.3048)
			(end -0.67945 0.3048)
			(stroke
				(width 0.1)
				(type default)
			)
			(layer "F.Fab")
		)
		(fp_line
			(start 0.120396 0.2794)
			(end -0.12065 0.2794)
			(stroke
				(width 0.1)
				(type default)
			)
			(layer "F.Fab")
		)
		(fp_line
			(start 0.120396 0.3048)
			(end 0.120396 0.2794)
			(stroke
				(width 0.1)
				(type default)
			)
			(layer "F.Fab")
		)
		(fp_line
			(start 0.12065 -0.3048)
			(end 0.67945 -0.3048)
			(stroke
				(width 0.1)
				(type default)
			)
			(layer "F.Fab")
		)
		(fp_line
			(start 0.12065 -0.2794)
			(end 0.12065 -0.3048)
			(stroke
				(width 0.1)
				(type default)
			)
			(layer "F.Fab")
		)
		(fp_line
			(start 0.67945 -0.3048)
			(end 0.67945 0.3048)
			(stroke
				(width 0.1)
				(type default)
			)
			(layer "F.Fab")
		)
		(fp_line
			(start 0.67945 0.3048)
			(end 0.120396 0.3048)
			(stroke
				(width 0.1)
				(type default)
			)
			(layer "F.Fab")
		)
		(pad "1" smd circle
			(at -0.40005 0)
			(size 0 0)
			(layers "F.Cu" "F.Mask" "F.Paste")
			(net "P12V_AUX")
		)
		(pad "2" smd circle
			(at 0.40005 0)
			(size 0 0)
			(layers "F.Cu" "F.Mask" "F.Paste")
			(net "GND")
		)
	)
)
